# T6G (Grand Teton) — schematic netlist excerpt (pin names and nets, part order shuffled) for the footprints in the layout excerpt that follows; sources: Cadence DE-HDL packaged netlist, KiCad conversion of 04192023_DAF0TMB3IC0_F0TG_MB_C_brd_V02_OCP.brd

C6082  Q_CAP  1UF 25V 10% X6S  pkg C0402  page 177 : A = P1V2_AUX ; B = GND
PC304_3  Q_CAP  22UF 4V 20% X6S  pkg C0805  page 212 : A = PVDDCR_CPU0_P1 ; B = GND
R6718  Q_RES  1K 1% CHIP  pkg 0201LF  page 184 : A = P1V8_CPU1_RT_1D ; B = SMB_RT_CPU1_P0_R_SDA

(kicad_pcb
	(version 20260206)
	(generator "pcbnew")
	(generator_version "10.0")
	(general
		(thickness 1.6)
		(legacy_teardrops no)
	)
	(paper "A4")
	(title_block
		(title "04192023_DAF0TMB3IC0_F0TG_MB_C_brd_V02_OCP.brd")
		(comment 1 "Grand Teton / footprints 6289-6291 of 8354")
	)
	(layers
		(0 "F.Cu" signal "TOP")
		(4 "In1.Cu" signal "GND")
		(6 "In2.Cu" signal "IN1")
		(8 "In3.Cu" signal "GND1")
		(10 "In4.Cu" signal "IN2")
		(12 "In5.Cu" signal "GND2")
		(14 "In6.Cu" signal "IN3")
		(16 "In7.Cu" signal "GND3")
		(18 "In8.Cu" signal "VCC")
		(20 "In9.Cu" signal "VCC1")
		(22 "In10.Cu" signal "GND4")
		(24 "In11.Cu" signal "IN4")
		(26 "In12.Cu" signal "GND5")
		(28 "In13.Cu" signal "IN5")
		(30 "In14.Cu" signal "GND6")
		(32 "In15.Cu" signal "IN6")
		(34 "In16.Cu" signal "GND7")
		(2 "B.Cu" signal "BOTTOM")
		(9 "F.Adhes" user "F.Adhesive")
		(11 "B.Adhes" user "B.Adhesive")
		(13 "F.Paste" user "Package Geometry/Pastemask Top")
		(15 "B.Paste" user "Package Geometry/Pastemask Bottom")
		(5 "F.SilkS" user "Ref Des/Silkscreen Top")
		(7 "B.SilkS" user "Ref Des/Silkscreen Bottom")
		(1 "F.Mask" user "Board Geometry/Soldermask Top")
		(3 "B.Mask" user "Board Geometry/Soldermask Bottom")
		(17 "Dwgs.User" user "User.Drawings")
		(19 "Cmts.User" user "User.Comments")
		(21 "Eco1.User" user "User.Eco1")
		(23 "Eco2.User" user "User.Eco2")
		(25 "Edge.Cuts" user "Board Geometry/Outline")
		(27 "Margin" user)
		(31 "F.CrtYd" user "Package Geometry/Place Bound Top")
		(29 "B.CrtYd" user "Package Geometry/Place Bound Bottom")
		(35 "F.Fab" user "Ref Des/Assembly Top")
		(33 "B.Fab" user "Ref Des/Assembly Bottom")
	)
	(footprint ""
		(layer "B.Cu")
		(at 101.92512 -191.278002 90)
		(property "Reference" "PC304_3"
			(at 0 0 90)
			(layer "B.SilkS")
			(hide yes)
			(effects
				(font
					(size 1.27 1.27)
				)
				(justify mirror)
			)
		)
		(property "Value" ""
			(at 0 0 90)
			(layer "B.Fab")
			(effects
				(font
					(size 1.27 1.27)
				)
				(justify mirror)
			)
		)
		(duplicate_pad_numbers_are_jumpers no)
		(fp_line
			(start 1.524 -0.762)
			(end -1.524 -0.762)
			(stroke
				(width 0.1524)
				(type default)
			)
			(layer "B.SilkS")
		)
		(fp_line
			(start -1.524 -0.762)
			(end -1.524 0.762)
			(stroke
				(width 0.1524)
				(type default)
			)
			(layer "B.SilkS")
		)
		(fp_line
			(start 1.524 0.762)
			(end 1.524 -0.762)
			(stroke
				(width 0.1524)
				(type default)
			)
			(layer "B.SilkS")
		)
		(fp_line
			(start -1.524 0.762)
			(end 1.524 0.762)
			(stroke
				(width 0.1524)
				(type default)
			)
			(layer "B.SilkS")
		)
		(fp_line
			(start 1.1049 -0.724916)
			(end 1.1049 0.724916)
			(stroke
				(width 0.1)
				(type default)
			)
			(layer "B.Fab")
		)
		(fp_line
			(start -1.1049 -0.724916)
			(end 1.1049 -0.724916)
			(stroke
				(width 0.1)
				(type default)
			)
			(layer "B.Fab")
		)
		(fp_line
			(start 1.1049 0.724916)
			(end -1.1049 0.724916)
			(stroke
				(width 0.1)
				(type default)
			)
			(layer "B.Fab")
		)
		(fp_line
			(start -1.1049 0.724916)
			(end -1.1049 -0.724916)
			(stroke
				(width 0.1)
				(type default)
			)
			(layer "B.Fab")
		)
		(pad "1" smd rect
			(at 0.889 0 90)
			(size 1.016 1.27)
			(layers "B.Cu" "B.Mask" "B.Paste")
			(net "PVDDCR_CPU0_P1")
		)
		(pad "2" smd rect
			(at -0.889 0 90)
			(size 1.016 1.27)
			(layers "B.Cu" "B.Mask" "B.Paste")
			(net "GND")
		)
	)
	(footprint ""
		(layer "B.Cu")
		(at 216.027 -333.883 -90)
		(property "Reference" "R6718"
			(at 0 0 90)
			(layer "B.SilkS")
			(hide yes)
			(effects
				(font
					(size 1.27 1.27)
				)
				(justify mirror)
			)
		)
		(property "Value" ""
			(at 0 0 90)
			(layer "B.Fab")
			(effects
				(font
					(size 1.27 1.27)
				)
				(justify mirror)
			)
		)
		(duplicate_pad_numbers_are_jumpers no)
		(fp_line
			(start -0.32512 0.175006)
			(end 0.32512 0.175006)
			(stroke
				(width 0.1)
				(type default)
			)
			(layer "B.Fab")
		)
		(fp_line
			(start 0.32512 0.175006)
			(end 0.32512 -0.175006)
			(stroke
				(width 0.1)
				(type default)
			)
			(layer "B.Fab")
		)
		(fp_line
			(start -0.32512 -0.175006)
			(end -0.32512 0.175006)
			(stroke
				(width 0.1)
				(type default)
			)
			(layer "B.Fab")
		)
		(fp_line
			(start 0.32512 -0.175006)
			(end -0.32512 -0.175006)
			(stroke
				(width 0.1)
				(type default)
			)
			(layer "B.Fab")
		)
		(pad "1" smd rect
			(at 0.2667 0 90)
			(size 0.3048 0.381)
			(layers "B.Cu" "B.Mask" "B.Paste")
			(net "P1V8_CPU1_RT_1D")
		)
		(pad "2" smd rect
			(at -0.2667 0 270)
			(size 0.3048 0.381)
			(layers "B.Cu" "B.Mask" "B.Paste")
			(net "SMB_RT_CPU1_P0_R_SDA")
		)
	)
	(footprint ""
		(layer "B.Cu")
		(at 129.305304 -32.638492)
		(property "Reference" "C6082"
			(at 0 0 0)
			(layer "B.SilkS")
			(hide yes)
			(effects
				(font
					(size 1.27 1.27)
				)
				(justify mirror)
			)
		)
		(property "Value" ""
			(at 0 0 0)
			(layer "B.Fab")
			(effects
				(font
					(size 1.27 1.27)
				)
				(justify mirror)
			)
		)
		(duplicate_pad_numbers_are_jumpers no)
		(fp_line
			(start -0.7874 -0.4064)
			(end -0.7874 0.4064)
			(stroke
				(width 0.1524)
				(type default)
			)
			(layer "B.SilkS")
		)
		(fp_line
			(start -0.7874 0.4064)
			(end 0.7874 0.4064)
			(stroke
				(width 0.1524)
				(type default)
			)
			(layer "B.SilkS")
		)
		(fp_line
			(start 0.7874 -0.4064)
			(end -0.7874 -0.4064)
			(stroke
				(width 0.1524)
				(type default)
			)
			(layer "B.SilkS")
		)
		(fp_line
			(start 0.7874 0.4064)
			(end 0.7874 -0.4064)
			(stroke
				(width 0.1524)
				(type default)
			)
			(layer "B.SilkS")
		)
		(fp_line
			(start -0.67945 -0.3048)
			(end -0.67945 0.3048)
			(stroke
				(width 0.1)
				(type default)
			)
			(layer "B.Fab")
		)
		(fp_line
			(start -0.67945 0.3048)
			(end -0.120396 0.3048)
			(stroke
				(width 0.1)
				(type default)
			)
			(layer "B.Fab")
		)
		(fp_line
			(start -0.12065 -0.3048)
			(end -0.67945 -0.3048)
			(stroke
				(width 0.1)
				(type default)
			)
			(layer "B.Fab")
		)
		(fp_line
			(start -0.12065 -0.2794)
			(end -0.12065 -0.3048)
			(stroke
				(width 0.1)
				(type default)
			)
			(layer "B.Fab")
		)
		(fp_line
			(start -0.120396 0.2794)
			(end 0.12065 0.2794)
			(stroke
				(width 0.1)
				(type default)
			)
			(layer "B.Fab")
		)
		(fp_line
			(start -0.120396 0.3048)
			(end -0.120396 0.2794)
			(stroke
				(width 0.1)
				(type default)
			)
			(layer "B.Fab")
		)
		(fp_line
			(start 0.12065 -0.305054)
			(end 0.12065 -0.2794)
			(stroke
				(width 0.1)
				(type default)
			)
			(layer "B.Fab")
		)
		(fp_line
			(start 0.12065 -0.2794)
			(end -0.12065 -0.2794)
			(stroke
				(width 0.1)
				(type default)
			)
			(layer "B.Fab")
		)
		(fp_line
			(start 0.12065 0.2794)
			(end 0.12065 0.3048)
			(stroke
				(width 0.1)
				(type default)
			)
			(layer "B.Fab")
		)
		(fp_line
			(start 0.12065 0.3048)
			(end 0.67945 0.3048)
			(stroke
				(width 0.1)
				(type default)
			)
			(layer "B.Fab")
		)
		(fp_line
			(start 0.67945 -0.305054)
			(end 0.12065 -0.305054)
			(stroke
				(width 0.1)
				(type default)
			)
			(layer "B.Fab")
		)
		(fp_line
			(start 0.67945 0.3048)
			(end 0.67945 -0.305054)
			(stroke
				(width 0.1)
				(type default)
			)
			(layer "B.Fab")
		)
		(pad "1" smd circle
			(at 0.40005 0 180)
			(size 0 0)
			(layers "B.Cu" "B.Mask" "B.Paste")
			(net "P1V2_AUX")
		)
		(pad "2" smd circle
			(at -0.40005 0 180)
			(size 0 0)
			(layers "B.Cu" "B.Mask" "B.Paste")
			(net "GND")
		)
	)
)
